(kicad_pcb
	(version 20260206)
	(generator "pcbnew")
	(generator_version "10.0")
	(general
		(thickness 1.6)
		(legacy_teardrops no)
	)
	(paper "A4")
	(title_block
		(title "fcb — Lightning_FCB_BRD.brd")
		(comment 1 "Lightning (Wiwynn / Facebook NVMe JBOF) / footprints 113-118 of 495")
	)
	(layers
		(0 "F.Cu" signal "TOP")
		(4 "In1.Cu" signal "L2GND")
		(6 "In2.Cu" signal "L3VCC")
		(2 "B.Cu" signal "BOTTOM")
		(9 "F.Adhes" user "F.Adhesive")
		(11 "B.Adhes" user "B.Adhesive")
		(13 "F.Paste" user "Package Geometry/Pastemask Top")
		(15 "B.Paste" user "Package Geometry/Pastemask Bottom")
		(5 "F.SilkS" user "Ref Des/Silkscreen Top")
		(7 "B.SilkS" user "Ref Des/Silkscreen Bottom")
		(1 "F.Mask" user "Board Geometry/Soldermask Top")
		(3 "B.Mask" user "Board Geometry/Soldermask Bottom")
		(17 "Dwgs.User" user "User.Drawings")
		(19 "Cmts.User" user "User.Comments")
		(21 "Eco1.User" user "User.Eco1")
		(23 "Eco2.User" user "User.Eco2")
		(25 "Edge.Cuts" user "Board Geometry/Outline")
		(27 "Margin" user)
		(31 "F.CrtYd" user "Package Geometry/Place Bound Top")
		(29 "B.CrtYd" user "Package Geometry/Place Bound Bottom")
		(35 "F.Fab" user "Ref Des/Assembly Top")
		(33 "B.Fab" user "Ref Des/Assembly Bottom")
	)
	(footprint ""
		(layer "F.Cu")
		(at 15.494 -60.5282 180)
		(property "Reference" "R359"
			(at 0 0 180)
			(layer "F.SilkS")
			(hide yes)
			(effects
				(font
					(size 1.27 1.27)
				)
			)
		)
		(property "Value" "10KR2F-2-GP"
			(at 0.064008 -3.993896 180)
			(unlocked yes)
			(layer "F.Fab")
			(hide yes)
			(effects
				(font
					(size 1.016 1.016)
					(thickness 0.1524)
				)
			)
		)
		(property "Device Type" "R402H16"
			(at 0.064008 -5.517896 180)
			(unlocked yes)
			(layer "F.Fab")
			(hide yes)
			(effects
				(font
					(size 1.016 1.016)
					(thickness 0.1524)
				)
			)
		)
		(duplicate_pad_numbers_are_jumpers no)
		(fp_line
			(start 0.508 -0.9398)
			(end -0.508 -0.9398)
			(stroke
				(width 0.1524)
				(type default)
			)
			(layer "F.SilkS")
		)
		(fp_line
			(start -0.508 -0.9398)
			(end -0.508 0.9398)
			(stroke
				(width 0.1524)
				(type default)
			)
			(layer "F.SilkS")
		)
		(fp_rect
			(start -0.508 0.9398)
			(end 0.508 -0.9398)
			(stroke
				(width 0)
				(type default)
			)
			(fill no)
			(layer "F.CrtYd")
		)
		(fp_rect
			(start -0.508 0.9398)
			(end 0.508 -0.9398)
			(stroke
				(width 0)
				(type default)
			)
			(fill no)
			(layer "F.Fab")
		)
		(pad "1" smd custom
			(at 0 -0.4445 180)
			(size 0.1397 0.1397)
			(layers "F.Cu" "F.Mask" "F.Paste")
			(net "P3V3")
			(options
				(clearance outline)
				(anchor circle)
			)
			(primitives
				(gr_poly
					(pts
						(arc
							(start -0.1778 -0.2794)
							(mid -0.249642 -0.249642)
							(end -0.2794 -0.1778)
						)
						(arc
							(start -0.2794 0.1778)
							(mid -0.249642 0.249642)
							(end -0.1778 0.2794)
						)
						(arc
							(start 0.1778 0.2794)
							(mid 0.249642 0.249642)
							(end 0.2794 0.1778)
						)
						(arc
							(start 0.2794 -0.1778)
							(mid 0.249642 -0.249642)
							(end 0.1778 -0.2794)
						)
					)
					(width 0)
					(fill yes)
				)
			)
		)
		(pad "2" smd custom
			(at 0 0.4445 180)
			(size 0.1397 0.1397)
			(layers "F.Cu" "F.Mask" "F.Paste")
			(net "UPPER_TRAY_ID")
			(options
				(clearance outline)
				(anchor circle)
			)
			(primitives
				(gr_poly
					(pts
						(arc
							(start -0.1778 -0.2794)
							(mid -0.249642 -0.249642)
							(end -0.2794 -0.1778)
						)
						(arc
							(start -0.2794 0.1778)
							(mid -0.249642 0.249642)
							(end -0.1778 0.2794)
						)
						(arc
							(start 0.1778 0.2794)
							(mid 0.249642 0.249642)
							(end 0.2794 0.1778)
						)
						(arc
							(start 0.2794 -0.1778)
							(mid 0.249642 -0.249642)
							(end 0.1778 -0.2794)
						)
					)
					(width 0)
					(fill yes)
				)
			)
		)
	)
	(footprint ""
		(layer "F.Cu")
		(at 33.401 -240.3094 180)
		(property "Reference" "R54"
			(at 0 0 180)
			(layer "F.SilkS")
			(hide yes)
			(effects
				(font
					(size 1.27 1.27)
				)
			)
		)
		(property "Value" "4K7R2J-2-GP"
			(at 0.064008 -3.993896 180)
			(unlocked yes)
			(layer "F.Fab")
			(hide yes)
			(effects
				(font
					(size 1.016 1.016)
					(thickness 0.1524)
				)
			)
		)
		(property "Device Type" "R402H16"
			(at 0.064008 -5.517896 180)
			(unlocked yes)
			(layer "F.Fab")
			(hide yes)
			(effects
				(font
					(size 1.016 1.016)
					(thickness 0.1524)
				)
			)
		)
		(duplicate_pad_numbers_are_jumpers no)
		(fp_line
			(start 0.508 -0.9398)
			(end -0.508 -0.9398)
			(stroke
				(width 0.1524)
				(type default)
			)
			(layer "F.SilkS")
		)
		(fp_line
			(start -0.508 -0.9398)
			(end -0.508 0.9398)
			(stroke
				(width 0.1524)
				(type default)
			)
			(layer "F.SilkS")
		)
		(fp_rect
			(start -0.508 0.9398)
			(end 0.508 -0.9398)
			(stroke
				(width 0)
				(type default)
			)
			(fill no)
			(layer "F.CrtYd")
		)
		(fp_rect
			(start -0.508 0.9398)
			(end 0.508 -0.9398)
			(stroke
				(width 0)
				(type default)
			)
			(fill no)
			(layer "F.Fab")
		)
		(pad "1" smd custom
			(at 0 -0.4445 180)
			(size 0.1397 0.1397)
			(layers "F.Cu" "F.Mask" "F.Paste")
			(net "GND")
			(options
				(clearance outline)
				(anchor circle)
			)
			(primitives
				(gr_poly
					(pts
						(arc
							(start -0.1778 -0.2794)
							(mid -0.249642 -0.249642)
							(end -0.2794 -0.1778)
						)
						(arc
							(start -0.2794 0.1778)
							(mid -0.249642 0.249642)
							(end -0.1778 0.2794)
						)
						(arc
							(start 0.1778 0.2794)
							(mid 0.249642 0.249642)
							(end 0.2794 0.1778)
						)
						(arc
							(start 0.2794 -0.1778)
							(mid 0.249642 -0.249642)
							(end 0.1778 -0.2794)
						)
					)
					(width 0)
					(fill yes)
				)
			)
		)
		(pad "2" smd custom
			(at 0 0.4445 180)
			(size 0.1397 0.1397)
			(layers "F.Cu" "F.Mask" "F.Paste")
			(net "LED_DRV_A0")
			(options
				(clearance outline)
				(anchor circle)
			)
			(primitives
				(gr_poly
					(pts
						(arc
							(start -0.1778 -0.2794)
							(mid -0.249642 -0.249642)
							(end -0.2794 -0.1778)
						)
						(arc
							(start -0.2794 0.1778)
							(mid -0.249642 0.249642)
							(end -0.1778 0.2794)
						)
						(arc
							(start 0.1778 0.2794)
							(mid 0.249642 0.249642)
							(end 0.2794 0.1778)
						)
						(arc
							(start 0.2794 -0.1778)
							(mid 0.249642 -0.249642)
							(end 0.1778 -0.2794)
						)
					)
					(width 0)
					(fill yes)
				)
			)
		)
	)
	(footprint ""
		(layer "F.Cu")
		(at 28.2956 -141.8082 90)
		(property "Reference" "PC97"
			(at 0 0 90)
			(layer "F.SilkS")
			(hide yes)
			(effects
				(font
					(size 1.27 1.27)
				)
			)
		)
		(property "Value" "SC10U25V5KX-GP"
			(at -0.0762 -6.1214 90)
			(unlocked yes)
			(layer "F.Fab")
			(hide yes)
			(effects
				(font
					(size 1.016 1.016)
					(thickness 0.1524)
				)
			)
		)
		(property "Device Type" "C805H56"
			(at -0.0762 -8.1534 90)
			(unlocked yes)
			(layer "F.Fab")
			(hide yes)
			(effects
				(font
					(size 1.016 1.016)
					(thickness 0.1524)
				)
			)
		)
		(duplicate_pad_numbers_are_jumpers no)
		(fp_line
			(start 0.635 0)
			(end -0.635 0)
			(stroke
				(width 0.508)
				(type default)
			)
			(layer "F.SilkS")
		)
		(fp_rect
			(start -0.9652 1.778)
			(end 0.9652 -1.778)
			(stroke
				(width 0)
				(type default)
			)
			(fill no)
			(layer "F.CrtYd")
		)
		(fp_poly
			(pts
				(xy -0.9652 -1.778) (xy 0.9652 -1.778) (xy 0.9652 1.778) (xy -0.9652 1.778)
			)
			(stroke
				(width 0)
				(type default)
			)
			(fill no)
			(layer "F.Fab")
		)
		(pad "1" smd rect
			(at 0 -0.9652 90)
			(size 1.397 1.143)
			(layers "F.Cu" "F.Mask" "F.Paste")
			(net "P12VU_2490_EN_2")
		)
		(pad "2" smd rect
			(at 0 0.9652 90)
			(size 1.397 1.143)
			(layers "F.Cu" "F.Mask" "F.Paste")
			(net "GND")
		)
	)
	(footprint ""
		(layer "F.Cu")
		(at 11.0236 -227.1776 180)
		(property "Reference" "R33"
			(at 0 0 180)
			(layer "F.SilkS")
			(hide yes)
			(effects
				(font
					(size 1.27 1.27)
				)
			)
		)
		(property "Value" "33R2F-3-GP"
			(at 0.064008 -3.993896 180)
			(unlocked yes)
			(layer "F.Fab")
			(hide yes)
			(effects
				(font
					(size 1.016 1.016)
					(thickness 0.1524)
				)
			)
		)
		(property "Device Type" "R402H16"
			(at 0.064008 -5.517896 180)
			(unlocked yes)
			(layer "F.Fab")
			(hide yes)
			(effects
				(font
					(size 1.016 1.016)
					(thickness 0.1524)
				)
			)
		)
		(duplicate_pad_numbers_are_jumpers no)
		(fp_line
			(start 0.508 -0.9398)
			(end -0.508 -0.9398)
			(stroke
				(width 0.1524)
				(type default)
			)
			(layer "F.SilkS")
		)
		(fp_line
			(start -0.508 -0.9398)
			(end -0.508 0.9398)
			(stroke
				(width 0.1524)
				(type default)
			)
			(layer "F.SilkS")
		)
		(fp_rect
			(start -0.508 0.9398)
			(end 0.508 -0.9398)
			(stroke
				(width 0)
				(type default)
			)
			(fill no)
			(layer "F.CrtYd")
		)
		(fp_rect
			(start -0.508 0.9398)
			(end 0.508 -0.9398)
			(stroke
				(width 0)
				(type default)
			)
			(fill no)
			(layer "F.Fab")
		)
		(pad "1" smd custom
			(at 0 -0.4445 180)
			(size 0.1397 0.1397)
			(layers "F.Cu" "F.Mask" "F.Paste")
			(net "P3V3")
			(options
				(clearance outline)
				(anchor circle)
			)
			(primitives
				(gr_poly
					(pts
						(arc
							(start -0.1778 -0.2794)
							(mid -0.249642 -0.249642)
							(end -0.2794 -0.1778)
						)
						(arc
							(start -0.2794 0.1778)
							(mid -0.249642 0.249642)
							(end -0.1778 0.2794)
						)
						(arc
							(start 0.1778 0.2794)
							(mid 0.249642 0.249642)
							(end 0.2794 0.1778)
						)
						(arc
							(start 0.2794 -0.1778)
							(mid 0.249642 -0.249642)
							(end 0.1778 -0.2794)
						)
					)
					(width 0)
					(fill yes)
				)
			)
		)
		(pad "2" smd custom
			(at 0 0.4445 180)
			(size 0.1397 0.1397)
			(layers "F.Cu" "F.Mask" "F.Paste")
			(net "LED_DR_LED3_BLUE")
			(options
				(clearance outline)
				(anchor circle)
			)
			(primitives
				(gr_poly
					(pts
						(arc
							(start -0.1778 -0.2794)
							(mid -0.249642 -0.249642)
							(end -0.2794 -0.1778)
						)
						(arc
							(start -0.2794 0.1778)
							(mid -0.249642 0.249642)
							(end -0.1778 0.2794)
						)
						(arc
							(start 0.1778 0.2794)
							(mid 0.249642 0.249642)
							(end 0.2794 0.1778)
						)
						(arc
							(start 0.2794 -0.1778)
							(mid 0.249642 -0.249642)
							(end 0.1778 -0.2794)
						)
					)
					(width 0)
					(fill yes)
				)
			)
		)
	)
	(footprint ""
		(layer "F.Cu")
		(at 34.3916 -184.4802)
		(property "Reference" "PQ10"
			(at 0 0 0)
			(layer "F.SilkS")
			(hide yes)
			(effects
				(font
					(size 1.27 1.27)
				)
			)
		)
		(property "Value" "PMBS3904-1-GP"
			(at 0 -9.0932 0)
			(unlocked yes)
			(layer "F.Fab")
			(hide yes)
			(effects
				(font
					(size 1.016 1.016)
					(thickness 0.1524)
				)
			)
		)
		(property "Device Type" "SOT-23-10H44"
			(at 0 -10.6172 0)
			(unlocked yes)
			(layer "F.Fab")
			(hide yes)
			(effects
				(font
					(size 1.016 1.016)
					(thickness 0.1524)
				)
			)
		)
		(duplicate_pad_numbers_are_jumpers no)
		(fp_line
			(start -1.7526 1.8796)
			(end -1.7526 0.9906)
			(stroke
				(width 0.3302)
				(type default)
			)
			(layer "F.SilkS")
		)
		(fp_line
			(start -1.651 -1.778)
			(end -1.651 1.778)
			(stroke
				(width 0.1524)
				(type default)
			)
			(layer "F.SilkS")
		)
		(fp_line
			(start -1.651 1.778)
			(end 1.651 1.778)
			(stroke
				(width 0.1524)
				(type default)
			)
			(layer "F.SilkS")
		)
		(fp_line
			(start -1.279398 2.152142)
			(end -0.9906 1.86309)
			(stroke
				(width 0.0127)
				(type default)
			)
			(layer "F.SilkS")
		)
		(fp_line
			(start -1.279144 2.15265)
			(end -0.701294 2.15265)
			(stroke
				(width 0.0127)
				(type default)
			)
			(layer "F.SilkS")
		)
		(fp_line
			(start -1.260856 2.1336)
			(end -0.720344 2.1336)
			(stroke
				(width 0.0127)
				(type default)
			)
			(layer "F.SilkS")
		)
		(fp_line
			(start -1.251458 2.124202)
			(end -0.729996 2.124202)
			(stroke
				(width 0.0127)
				(type default)
			)
			(layer "F.SilkS")
		)
		(fp_line
			(start -1.241806 2.11455)
			(end -0.739394 2.11455)
			(stroke
				(width 0.0127)
				(type default)
			)
			(layer "F.SilkS")
		)
		(fp_line
			(start -1.232408 2.105152)
			(end -0.749046 2.105152)
			(stroke
				(width 0.0127)
				(type default)
			)
			(layer "F.SilkS")
		)
		(fp_line
			(start -1.222756 2.0955)
			(end -0.758444 2.0955)
			(stroke
				(width 0.0127)
				(type default)
			)
			(layer "F.SilkS")
		)
		(fp_line
			(start -1.213358 2.086102)
			(end -0.768096 2.086102)
			(stroke
				(width 0.0127)
				(type default)
			)
			(layer "F.SilkS")
		)
		(fp_line
			(start -1.203706 2.07645)
			(end -0.777494 2.07645)
			(stroke
				(width 0.0127)
				(type default)
			)
			(layer "F.SilkS")
		)
		(fp_line
			(start -1.194308 2.067052)
			(end -0.787146 2.067052)
			(stroke
				(width 0.0127)
				(type default)
			)
			(layer "F.SilkS")
		)
		(fp_line
			(start -1.184656 2.0574)
			(end -0.796544 2.0574)
			(stroke
				(width 0.0127)
				(type default)
			)
			(layer "F.SilkS")
		)
		(fp_line
			(start -1.175258 2.048002)
			(end -0.806196 2.048002)
			(stroke
				(width 0.0127)
				(type default)
			)
			(layer "F.SilkS")
		)
		(fp_line
			(start -1.165606 2.03835)
			(end -0.815594 2.03835)
			(stroke
				(width 0.0127)
				(type default)
			)
			(layer "F.SilkS")
		)
		(fp_line
			(start -1.156208 2.028952)
			(end -0.825246 2.028952)
			(stroke
				(width 0.0127)
				(type default)
			)
			(layer "F.SilkS")
		)
		(fp_line
			(start -1.146556 2.0193)
			(end -0.834644 2.0193)
			(stroke
				(width 0.0127)
				(type default)
			)
			(layer "F.SilkS")
		)
		(fp_line
			(start -1.137158 2.009902)
			(end -0.844296 2.009902)
			(stroke
				(width 0.0127)
				(type default)
			)
			(layer "F.SilkS")
		)
		(fp_line
			(start -1.127506 2.00025)
			(end -0.853694 2.00025)
			(stroke
				(width 0.0127)
				(type default)
			)
			(layer "F.SilkS")
		)
		(fp_line
			(start -1.118108 1.990852)
			(end -0.863346 1.990852)
			(stroke
				(width 0.0127)
				(type default)
			)
			(layer "F.SilkS")
		)
		(fp_line
			(start -1.108456 1.9812)
			(end -0.872744 1.9812)
			(stroke
				(width 0.0127)
				(type default)
			)
			(layer "F.SilkS")
		)
		(fp_line
			(start -1.099058 1.971802)
			(end -0.882396 1.971802)
			(stroke
				(width 0.0127)
				(type default)
			)
			(layer "F.SilkS")
		)
		(fp_line
			(start -1.089406 1.96215)
			(end -0.891794 1.96215)
			(stroke
				(width 0.0127)
				(type default)
			)
			(layer "F.SilkS")
		)
		(fp_line
			(start -1.080008 1.952752)
			(end -0.901446 1.952752)
			(stroke
				(width 0.0127)
				(type default)
			)
			(layer "F.SilkS")
		)
		(fp_line
			(start -1.070356 1.9431)
			(end -0.910844 1.9431)
			(stroke
				(width 0.0127)
				(type default)
			)
			(layer "F.SilkS")
		)
		(fp_line
			(start -1.060958 1.933702)
			(end -0.920496 1.933702)
			(stroke
				(width 0.0127)
				(type default)
			)
			(layer "F.SilkS")
		)
		(fp_line
			(start -1.051306 1.92405)
			(end -0.929894 1.92405)
			(stroke
				(width 0.0127)
				(type default)
			)
			(layer "F.SilkS")
		)
		(fp_line
			(start -1.041908 1.914652)
			(end -0.939546 1.914652)
			(stroke
				(width 0.0127)
				(type default)
			)
			(layer "F.SilkS")
		)
		(fp_line
			(start -1.032256 1.905)
			(end -0.948944 1.905)
			(stroke
				(width 0.0127)
				(type default)
			)
			(layer "F.SilkS")
		)
		(fp_line
			(start -1.022858 1.895602)
			(end -0.958596 1.895602)
			(stroke
				(width 0.0127)
				(type default)
			)
			(layer "F.SilkS")
		)
		(fp_line
			(start -1.013206 1.88595)
			(end -0.967994 1.88595)
			(stroke
				(width 0.0127)
				(type default)
			)
			(layer "F.SilkS")
		)
		(fp_line
			(start -1.003808 1.876552)
			(end -0.977646 1.876552)
			(stroke
				(width 0.0127)
				(type default)
			)
			(layer "F.SilkS")
		)
		(fp_line
			(start -0.994156 1.8669)
			(end -0.987044 1.8669)
			(stroke
				(width 0.0127)
				(type default)
			)
			(layer "F.SilkS")
		)
		(fp_line
			(start -0.9906 1.86309)
			(end -0.701294 2.15265)
			(stroke
				(width 0.0127)
				(type default)
			)
			(layer "F.SilkS")
		)
		(fp_line
			(start -0.719074 2.145538)
			(end -1.265936 2.14122)
			(stroke
				(width 0.0127)
				(type default)
			)
			(layer "F.SilkS")
		)
		(fp_line
			(start -0.71628 2.15265)
			(end -1.26492 2.15265)
			(stroke
				(width 0.0127)
				(type default)
			)
			(layer "F.SilkS")
		)
		(fp_line
			(start -0.635 1.8796)
			(end -1.7526 1.8796)
			(stroke
				(width 0.3302)
				(type default)
			)
			(layer "F.SilkS")
		)
		(fp_line
			(start 1.651 -1.778)
			(end -1.651 -1.778)
			(stroke
				(width 0.1524)
				(type default)
			)
			(layer "F.SilkS")
		)
		(fp_line
			(start 1.651 1.778)
			(end 1.651 -1.778)
			(stroke
				(width 0.1524)
				(type default)
			)
			(layer "F.SilkS")
		)
		(fp_poly
			(pts
				(xy -1.285748 2.159) (xy -1.285748 1.8796) (xy -1.778 1.8796) (xy -1.778 -1.8796) (xy 1.778 -1.8796)
				(xy 1.778 1.8796) (xy -0.694944 1.8796) (xy -0.694944 2.159)
			)
			(stroke
				(width 0)
				(type default)
			)
			(fill no)
			(layer "F.CrtYd")
		)
		(fp_poly
			(pts
				(xy -1.285748 2.159) (xy -1.285748 1.8796) (xy -1.778 1.8796) (xy -1.778 -1.8796) (xy 1.778 -1.8796)
				(xy 1.778 1.8796) (xy -0.694944 1.8796) (xy -0.694944 2.159)
			)
			(stroke
				(width 0)
				(type default)
			)
			(fill no)
			(layer "F.Fab")
		)
		(pad "1" smd rect
			(at -0.98425 0.9525)
			(size 0.762 1.143)
			(layers "F.Cu" "F.Mask" "F.Paste")
			(net "P3V3_AUX_BJT_B")
		)
		(pad "2" smd rect
			(at 0.98425 0.9525)
			(size 0.762 1.143)
			(layers "F.Cu" "F.Mask" "F.Paste")
			(net "P3V3_AUX")
		)
		(pad "3" smd rect
			(at 0 -0.9525)
			(size 0.762 1.143)
			(layers "F.Cu" "F.Mask" "F.Paste")
			(net "P12V_AUX")
		)
	)
	(footprint ""
		(layer "F.Cu")
		(at 33.401 -363.728 -90)
		(property "Reference" "C51"
			(at 0 0 270)
			(layer "F.SilkS")
			(hide yes)
			(effects
				(font
					(size 1.27 1.27)
				)
			)
		)
		(property "Value" "SCD1U10V2KX-4-LL-GP"
			(at 1.1811 -2.7051 270)
			(unlocked yes)
			(layer "F.Fab")
			(hide yes)
			(effects
				(font
					(size 1.016 1.016)
					(thickness 0.1524)
				)
			)
		)
		(property "Device Type" "C402H22"
			(at 1.1811 -4.2291 270)
			(unlocked yes)
			(layer "F.Fab")
			(hide yes)
			(effects
				(font
					(size 1.016 1.016)
					(thickness 0.1524)
				)
			)
		)
		(duplicate_pad_numbers_are_jumpers no)
		(fp_rect
			(start -0.4318 0.9525)
			(end 0.4318 -0.9525)
			(stroke
				(width 0)
				(type default)
			)
			(fill no)
			(layer "F.CrtYd")
		)
		(fp_rect
			(start -0.4318 0.9525)
			(end 0.4318 -0.9525)
			(stroke
				(width 0)
				(type default)
			)
			(fill no)
			(layer "F.Fab")
		)
		(pad "1" smd custom
			(at 0 -0.4445 270)
			(size 0.1524 0.1524)
			(layers "F.Cu" "F.Mask" "F.Paste")
			(net "TEMP_ALM#_REVERSE_R")
			(options
				(clearance outline)
				(anchor circle)
			)
			(primitives
				(gr_poly
					(pts
						(arc
							(start 0.3048 -0.2032)
							(mid 0.275042 -0.275042)
							(end 0.2032 -0.3048)
						)
						(arc
							(start -0.2032 -0.3048)
							(mid -0.275042 -0.275042)
							(end -0.3048 -0.2032)
						)
						(arc
							(start -0.3048 0.2032)
							(mid -0.275042 0.275042)
							(end -0.2032 0.3048)
						)
						(arc
							(start 0.2032 0.3048)
							(mid 0.275042 0.275042)
							(end 0.3048 0.2032)
						)
					)
					(width 0)
					(fill yes)
				)
			)
		)
		(pad "2" smd custom
			(at 0 0.4445 270)
			(size 0.1524 0.1524)
			(layers "F.Cu" "F.Mask" "F.Paste")
			(net "GND")
			(options
				(clearance outline)
				(anchor circle)
			)
			(primitives
				(gr_poly
					(pts
						(arc
							(start 0.3048 -0.2032)
							(mid 0.275042 -0.275042)
							(end 0.2032 -0.3048)
						)
						(arc
							(start -0.2032 -0.3048)
							(mid -0.275042 -0.275042)
							(end -0.3048 -0.2032)
						)
						(arc
							(start -0.3048 0.2032)
							(mid -0.275042 0.275042)
							(end -0.2032 0.3048)
						)
						(arc
							(start 0.2032 0.3048)
							(mid 0.275042 0.275042)
							(end 0.3048 0.2032)
						)
					)
					(width 0)
					(fill yes)
				)
			)
		)
	)
)
